#ISCELL
  mstr_misc dns *
  *
#ISCELL
  pure_quanta quanta_title_block_c *
  *
#ISCELL
  standard offpage *
  page200_i1
#CELL
  pure_quanta q_cap *
  page200_i10
#ISCELL
  pure_quanta_power universal_gnd *
  page200_i11
#CELL
  pure_quanta q_res *
  page200_i12
#ISCELL
  standard offpage *
  page200_i13
#CELL
  pure_quanta q_res *
  page200_i14
#ISCELL
  pure_quanta_power vcc_core *
  page200_i15
#ISCELL
  pure_quanta_power universal_gnd *
  page200_i16
#CELL
  pure_quanta q_cap *
  page200_i17
#ISCELL
  pure_quanta_power universal_gnd *
  page200_i18
#ISCELL
  pure_quanta_power universal_gnd *
  page200_i19
#ISCELL
  standard offpage *
  page200_i2
#ISCELL
  standard offpage *
  page200_i20
#ISCELL
  standard offpage *
  page200_i21
#CELL
  pure_quanta isl99390frztr5935 *
  page200_i22
#ISCELL
  pure_quanta_power universal_gnd *
  page200_i23
#ISCELL
  pure_quanta_power universal_gnd *
  page200_i24
#CELL
  pure_quanta q_res *
  page200_i25
#CELL
  pure_quanta q_res *
  page200_i26
#CELL
  pure_quanta q_cap *
  page200_i27
#ISCELL
  pure_quanta_power universal_gnd *
  page200_i28
#CELL
  pure_quanta q_cap *
  page200_i29
#CELL
  pure_quanta q_res *
  page200_i3
#CELL
  pure_quanta q_cap *
  page200_i30
#CELL
  pure_quanta q_cap *
  page200_i31
#ISCELL
  pure_quanta_power universal_gnd *
  page200_i32
#CELL
  pure_quanta q_res *
  page200_i33
#CELL
  pure_quanta q_cap *
  page200_i34
#ISCELL
  pure_quanta_power universal_gnd *
  page200_i35
#CELL
  pure_quanta q_cap *
  page200_i36
#CELL
  pure_quanta q_res *
  page200_i37
#ISCELL
  standard offpage *
  page200_i38
#ISCELL
  pure_quanta_power universal_gnd *
  page200_i39
#ISCELL
  pure_quanta_power vcc_core *
  page200_i4
#CELL
  pure_quanta q_res *
  page200_i40
#CELL
  pure_quanta q_res *
  page200_i41
#ISCELL
  pure_quanta_power vcc_core *
  page200_i42
#CELL
  pure_quanta q_cap *
  page200_i43
#ISCELL
  pure_quanta_power vcc_core *
  page200_i44
#CELL
  pure_quanta q_cap *
  page200_i45
#CELL
  pure_quanta q_cap *
  page200_i46
#CELL
  pure_quanta q_res *
  page200_i47
#CELL
  pure_quanta q_cap *
  page200_i48
#CELL
  pure_quanta q_cap *
  page200_i49
#ISCELL
  pure_quanta_power universal_gnd *
  page200_i5
#CELL
  pure_quanta q_cap *
  page200_i50
#CELL
  pure_quanta q_cap *
  page200_i51
#CELL
  pure_quanta q_cap *
  page200_i52
#CELL
  pure_quanta q_res *
  page200_i53
#CELL
  pure_quanta q_cap *
  page200_i54
#CELL
  pure_quanta q_inductor *
  page200_i55
#CELL
  pure_quanta q_cap *
  page200_i56
#ISCELL
  pure_quanta_power universal_gnd *
  page200_i57
#CELL
  pure_quanta q_cap *
  page200_i58
#ISCELL
  pure_quanta_power vcc_core *
  page200_i59
#ISCELL
  standard offpage *
  page200_i6
#CELL
  pure_quanta q_res *
  page200_i60
#ISCELL
  pure_quanta_power universal_gnd *
  page200_i61
#CELL
  pure_quanta q_capp *
  page200_i62
#CELL
  pure_quanta q_capp *
  page200_i63
#ISCELL
  pure_quanta_power vcc_core *
  page200_i64
#CELL
  pure_quanta q_capp *
  page200_i65
#ISCELL
  pure_quanta_power universal_gnd *
  page200_i66
#CELL
  pure_quanta q_cap *
  page200_i67
#ISCELL
  pure_quanta_power vcc_core *
  page200_i68
#CELL
  pure_quanta q_capp *
  page200_i69
#ISCELL
  standard offpage *
  page200_i7
#ISCELL
  pure_quanta_power universal_gnd *
  page200_i70
#ISCELL
  pure_quanta_power vcc_core *
  page200_i71
#CELL
  pure_quanta q_capp *
  page200_i72
#CELL
  pure_quanta q_capp *
  page200_i73
#ISCELL
  pure_quanta_power universal_gnd *
  page200_i74
#CELL
  pure_quanta q_capp *
  page200_i75
#CELL
  pure_quanta q_cap *
  page200_i76
#ISCELL
  pure_quanta_power universal_gnd *
  page200_i77
#CELL
  pure_quanta q_inductor *
  page200_i78
#ISCELL
  pure_quanta_power vcc_core *
  page200_i79
#CELL
  pure_quanta q_cap *
  page200_i8
#CELL
  pure_quanta q_cap *
  page200_i80
#CELL
  pure_quanta q_capp *
  page200_i81
#CELL
  pure_quanta q_cap *
  page200_i82
#ISCELL
  pure_quanta_power universal_gnd *
  page200_i83
#CELL
  pure_quanta q_inductor *
  page200_i84
#CELL
  pure_quanta q_cap *
  page200_i85
#ISCELL
  pure_quanta_power vcc_core *
  page200_i86
#CELL
  pure_quanta q_cap *
  page200_i87
#CELL
  pure_quanta q_cap *
  page200_i88
#CELL
  pure_quanta q_res *
  page200_i89
#ISCELL
  pure_quanta_power universal_gnd *
  page200_i9
#ISCELL
  pure_quanta_power vcc_core *
  page200_i90
#CELL
  pure_quanta q_cap *
  page200_i91
#CELL
  pure_quanta isl99390frztr5935 *
  page200_i92
#CELL
  pure_quanta q_cap *
  page200_i93
#CELL
  pure_quanta q_cap *
  page200_i94
#CELL
  pure_quanta q_cap *
  page200_i95
